# S9S_MB_2U (Grand Teton) — schematic netlist excerpt (pin names and nets, part order shuffled) for the footprints in the layout excerpt that follows; sources: Cadence DE-HDL packaged netlist, KiCad conversion of 03242023_DA0F0TMBIJ0_F0T_Motherboard_J_brd_V01_OCP.brd

R301  Q_RES  301 1% CHIP  pkg 0402LF  page 118 : A = PVNN_TERM_CPU0 ; B = H_CPU_RMCA_LVC1_R_N
C2034  Q_CAP  0.1UF 25V 10% X7R  pkg 0402  page 152 : A = P3V3_AUX_USB_HUB ; B = GND

(kicad_pcb
	(version 20260206)
	(generator "pcbnew")
	(generator_version "10.0")
	(general
		(thickness 1.6)
		(legacy_teardrops no)
	)
	(paper "A4")
	(title_block
		(title "03242023_DA0F0TMBIJ0_F0T_Motherboard_J_brd_V01_OCP.brd")
		(comment 1 "Grand Teton / footprints 5990-5991 of 6105")
	)
	(layers
		(0 "F.Cu" signal "TOP")
		(4 "In1.Cu" signal "GND")
		(6 "In2.Cu" signal "IN1")
		(8 "In3.Cu" signal "GND1")
		(10 "In4.Cu" signal "IN2")
		(12 "In5.Cu" signal "GND2")
		(14 "In6.Cu" signal "IN3")
		(16 "In7.Cu" signal "GND3")
		(18 "In8.Cu" signal "VCC")
		(20 "In9.Cu" signal "VCC1")
		(22 "In10.Cu" signal "GND4")
		(24 "In11.Cu" signal "IN4")
		(26 "In12.Cu" signal "GND5")
		(28 "In13.Cu" signal "IN5")
		(30 "In14.Cu" signal "GND6")
		(32 "In15.Cu" signal "IN6")
		(34 "In16.Cu" signal "GND7")
		(2 "B.Cu" signal "BOTTOM")
		(9 "F.Adhes" user "F.Adhesive")
		(11 "B.Adhes" user "B.Adhesive")
		(13 "F.Paste" user "Package Geometry/Pastemask Top")
		(15 "B.Paste" user "Package Geometry/Pastemask Bottom")
		(5 "F.SilkS" user "Ref Des/Silkscreen Top")
		(7 "B.SilkS" user "Ref Des/Silkscreen Bottom")
		(1 "F.Mask" user "Board Geometry/Soldermask Top")
		(3 "B.Mask" user "Board Geometry/Soldermask Bottom")
		(17 "Dwgs.User" user "User.Drawings")
		(19 "Cmts.User" user "User.Comments")
		(21 "Eco1.User" user "User.Eco1")
		(23 "Eco2.User" user "User.Eco2")
		(25 "Edge.Cuts" user "Board Geometry/Outline")
		(27 "Margin" user)
		(31 "F.CrtYd" user "Package Geometry/Place Bound Top")
		(29 "B.CrtYd" user "Package Geometry/Place Bound Bottom")
		(35 "F.Fab" user "Ref Des/Assembly Top")
		(33 "B.Fab" user "Ref Des/Assembly Bottom")
	)
	(footprint ""
		(layer "B.Cu")
		(at 11.961114 -98.296222 180)
		(property "Reference" "C2034"
			(at 0 0 0)
			(layer "B.SilkS")
			(hide yes)
			(effects
				(font
					(size 1.27 1.27)
				)
				(justify mirror)
			)
		)
		(property "Value" ""
			(at 0 0 0)
			(layer "B.Fab")
			(effects
				(font
					(size 1.27 1.27)
				)
				(justify mirror)
			)
		)
		(duplicate_pad_numbers_are_jumpers no)
		(fp_line
			(start 0.7874 0.4064)
			(end 0.7874 -0.4064)
			(stroke
				(width 0.1524)
				(type default)
			)
			(layer "B.SilkS")
		)
		(fp_line
			(start 0.7874 -0.4064)
			(end -0.7874 -0.4064)
			(stroke
				(width 0.1524)
				(type default)
			)
			(layer "B.SilkS")
		)
		(fp_line
			(start -0.7874 0.4064)
			(end 0.7874 0.4064)
			(stroke
				(width 0.1524)
				(type default)
			)
			(layer "B.SilkS")
		)
		(fp_line
			(start -0.7874 -0.4064)
			(end -0.7874 0.4064)
			(stroke
				(width 0.1524)
				(type default)
			)
			(layer "B.SilkS")
		)
		(fp_line
			(start 0.67945 0.3048)
			(end 0.67945 -0.305054)
			(stroke
				(width 0.1)
				(type default)
			)
			(layer "B.Fab")
		)
		(fp_line
			(start 0.67945 -0.305054)
			(end 0.12065 -0.305054)
			(stroke
				(width 0.1)
				(type default)
			)
			(layer "B.Fab")
		)
		(fp_line
			(start 0.12065 0.3048)
			(end 0.67945 0.3048)
			(stroke
				(width 0.1)
				(type default)
			)
			(layer "B.Fab")
		)
		(fp_line
			(start 0.12065 0.2794)
			(end 0.12065 0.3048)
			(stroke
				(width 0.1)
				(type default)
			)
			(layer "B.Fab")
		)
		(fp_line
			(start 0.12065 -0.2794)
			(end -0.12065 -0.2794)
			(stroke
				(width 0.1)
				(type default)
			)
			(layer "B.Fab")
		)
		(fp_line
			(start 0.12065 -0.305054)
			(end 0.12065 -0.2794)
			(stroke
				(width 0.1)
				(type default)
			)
			(layer "B.Fab")
		)
		(fp_line
			(start -0.120396 0.3048)
			(end -0.120396 0.2794)
			(stroke
				(width 0.1)
				(type default)
			)
			(layer "B.Fab")
		)
		(fp_line
			(start -0.120396 0.2794)
			(end 0.12065 0.2794)
			(stroke
				(width 0.1)
				(type default)
			)
			(layer "B.Fab")
		)
		(fp_line
			(start -0.12065 -0.2794)
			(end -0.12065 -0.3048)
			(stroke
				(width 0.1)
				(type default)
			)
			(layer "B.Fab")
		)
		(fp_line
			(start -0.12065 -0.3048)
			(end -0.67945 -0.3048)
			(stroke
				(width 0.1)
				(type default)
			)
			(layer "B.Fab")
		)
		(fp_line
			(start -0.67945 0.3048)
			(end -0.120396 0.3048)
			(stroke
				(width 0.1)
				(type default)
			)
			(layer "B.Fab")
		)
		(fp_line
			(start -0.67945 -0.3048)
			(end -0.67945 0.3048)
			(stroke
				(width 0.1)
				(type default)
			)
			(layer "B.Fab")
		)
		(pad "1" smd circle
			(at 0.40005 0)
			(size 0 0)
			(layers "B.Cu" "B.Mask" "B.Paste")
			(net "P3V3_AUX_USB_HUB")
		)
		(pad "2" smd circle
			(at -0.40005 0)
			(size 0 0)
			(layers "B.Cu" "B.Mask" "B.Paste")
			(net "GND")
		)
	)
	(footprint ""
		(layer "B.Cu")
		(at 323.407278 -186.70651 -90)
		(property "Reference" "R301"
			(at 0 0 90)
			(layer "B.SilkS")
			(hide yes)
			(effects
				(font
					(size 1.27 1.27)
				)
				(justify mirror)
			)
		)
		(property "Value" ""
			(at 0 0 90)
			(layer "B.Fab")
			(effects
				(font
					(size 1.27 1.27)
				)
				(justify mirror)
			)
		)
		(duplicate_pad_numbers_are_jumpers no)
		(fp_line
			(start -0.7874 0.4064)
			(end 0.7874 0.4064)
			(stroke
				(width 0.1524)
				(type default)
			)
			(layer "B.SilkS")
		)
		(fp_line
			(start 0.7874 0.4064)
			(end 0.7874 -0.4064)
			(stroke
				(width 0.1524)
				(type default)
			)
			(layer "B.SilkS")
		)
		(fp_line
			(start -0.7874 -0.4064)
			(end -0.7874 0.4064)
			(stroke
				(width 0.1524)
				(type default)
			)
			(layer "B.SilkS")
		)
		(fp_line
			(start 0.7874 -0.4064)
			(end -0.7874 -0.4064)
			(stroke
				(width 0.1524)
				(type default)
			)
			(layer "B.SilkS")
		)
		(fp_line
			(start -0.67945 0.3048)
			(end -0.120396 0.3048)
			(stroke
				(width 0.1)
				(type default)
			)
			(layer "B.Fab")
		)
		(fp_line
			(start -0.120396 0.3048)
			(end -0.120396 0.2794)
			(stroke
				(width 0.1)
				(type default)
			)
			(layer "B.Fab")
		)
		(fp_line
			(start 0.12065 0.3048)
			(end 0.67945 0.3048)
			(stroke
				(width 0.1)
				(type default)
			)
			(layer "B.Fab")
		)
		(fp_line
			(start 0.67945 0.3048)
			(end 0.67945 -0.305054)
			(stroke
				(width 0.1)
				(type default)
			)
			(layer "B.Fab")
		)
		(fp_line
			(start -0.120396 0.2794)
			(end 0.12065 0.2794)
			(stroke
				(width 0.1)
				(type default)
			)
			(layer "B.Fab")
		)
		(fp_line
			(start 0.12065 0.2794)
			(end 0.12065 0.3048)
			(stroke
				(width 0.1)
				(type default)
			)
			(layer "B.Fab")
		)
		(fp_line
			(start -0.12065 -0.2794)
			(end -0.12065 -0.3048)
			(stroke
				(width 0.1)
				(type default)
			)
			(layer "B.Fab")
		)
		(fp_line
			(start 0.12065 -0.2794)
			(end -0.12065 -0.2794)
			(stroke
				(width 0.1)
				(type default)
			)
			(layer "B.Fab")
		)
		(fp_line
			(start -0.67945 -0.3048)
			(end -0.67945 0.3048)
			(stroke
				(width 0.1)
				(type default)
			)
			(layer "B.Fab")
		)
		(fp_line
			(start -0.12065 -0.3048)
			(end -0.67945 -0.3048)
			(stroke
				(width 0.1)
				(type default)
			)
			(layer "B.Fab")
		)
		(fp_line
			(start 0.12065 -0.305054)
			(end 0.12065 -0.2794)
			(stroke
				(width 0.1)
				(type default)
			)
			(layer "B.Fab")
		)
		(fp_line
			(start 0.67945 -0.305054)
			(end 0.12065 -0.305054)
			(stroke
				(width 0.1)
				(type default)
			)
			(layer "B.Fab")
		)
		(pad "1" smd circle
			(at 0.40005 0 90)
			(size 0 0)
			(layers "B.Cu" "B.Mask" "B.Paste")
			(net "PVNN_TERM_CPU0")
		)
		(pad "2" smd circle
			(at -0.40005 0 90)
			(size 0 0)
			(layers "B.Cu" "B.Mask" "B.Paste")
			(net "H_CPU_RMCA_LVC1_R_N")
		)
	)
)
